# BASEBOARD_FAB2 (Tioga Pass) — schematic netlist excerpt (pin names and nets, part order shuffled) for the footprints in the layout excerpt that follows; sources: Cadence DE-HDL packaged netlist, KiCad conversion of Wiwynn_Tioga_Pass_MB.brd

C1D16  CAP  0.22UF 16V 10% X7R  pkg 0402  page 208 : A = P5V_STBY ; B = GND
C5G11  CAP_A  47UF 4V 20% X5R  pkg 0603V  page 217 : A = PVDDQ_ABC ; B = GND
R2L4  RES  2.0K 1% CHIP  pkg 0402  page 178 : A = P3V3_STBY ; B = SGPIO_PCH_SSATA_DOUT0_R

(kicad_pcb
	(version 20260206)
	(generator "pcbnew")
	(generator_version "10.0")
	(general
		(thickness 1.6)
		(legacy_teardrops no)
	)
	(paper "A4")
	(title_block
		(title "Wiwynn_Tioga_Pass_MB.brd")
		(comment 1 "Tioga Pass / footprints 1058-1060 of 4770")
	)
	(layers
		(0 "F.Cu" signal "TOP")
		(4 "In1.Cu" signal "L2GND")
		(6 "In2.Cu" signal "L3")
		(8 "In3.Cu" signal "L4GND")
		(10 "In4.Cu" signal "L5")
		(12 "In5.Cu" signal "L6GND")
		(14 "In6.Cu" signal "L7VCC")
		(16 "In7.Cu" signal "L8VCC")
		(18 "In8.Cu" signal "L9GND")
		(20 "In9.Cu" signal "L10")
		(22 "In10.Cu" signal "L11GND")
		(24 "In11.Cu" signal "L12")
		(26 "In12.Cu" signal "L13GND")
		(2 "B.Cu" signal "BOTTOM")
		(9 "F.Adhes" user "F.Adhesive")
		(11 "B.Adhes" user "B.Adhesive")
		(13 "F.Paste" user "Package Geometry/Pastemask Top")
		(15 "B.Paste" user "Package Geometry/Pastemask Bottom")
		(5 "F.SilkS" user "Ref Des/Silkscreen Top")
		(7 "B.SilkS" user "Ref Des/Silkscreen Bottom")
		(1 "F.Mask" user "Board Geometry/Soldermask Top")
		(3 "B.Mask" user "Board Geometry/Soldermask Bottom")
		(17 "Dwgs.User" user "User.Drawings")
		(19 "Cmts.User" user "User.Comments")
		(21 "Eco1.User" user "User.Eco1")
		(23 "Eco2.User" user "User.Eco2")
		(25 "Edge.Cuts" user "Board Geometry/Outline")
		(27 "Margin" user)
		(31 "F.CrtYd" user "Package Geometry/Place Bound Top")
		(29 "B.CrtYd" user "Package Geometry/Place Bound Bottom")
		(35 "F.Fab" user "Ref Des/Assembly Top")
		(33 "B.Fab" user "Ref Des/Assembly Bottom")
	)
	(footprint ""
		(layer "F.Cu")
		(at 33.127696 -69.4182 90)
		(property "Reference" "C1D16"
			(at 0 0 90)
			(layer "F.SilkS")
			(hide yes)
			(effects
				(font
					(size 1.27 1.27)
				)
			)
		)
		(property "Value" ""
			(at 0 0 90)
			(layer "F.Fab")
			(effects
				(font
					(size 1.27 1.27)
				)
			)
		)
		(duplicate_pad_numbers_are_jumpers no)
		(fp_rect
			(start 0.3048 0.9906)
			(end -0.3048 -0.1016)
			(stroke
				(width 0)
				(type default)
			)
			(fill no)
			(layer "F.CrtYd")
		)
		(fp_line
			(start 0.3048 -0.1016)
			(end -0.3048 -0.1016)
			(stroke
				(width 0.1)
				(type default)
			)
			(layer "F.Fab")
		)
		(fp_line
			(start -0.3048 -0.1016)
			(end -0.3048 0.9906)
			(stroke
				(width 0.1)
				(type default)
			)
			(layer "F.Fab")
		)
		(fp_line
			(start 0.3048 0.9906)
			(end 0.3048 -0.1016)
			(stroke
				(width 0.1)
				(type default)
			)
			(layer "F.Fab")
		)
		(fp_line
			(start -0.3048 0.9906)
			(end 0.3048 0.9906)
			(stroke
				(width 0.1)
				(type default)
			)
			(layer "F.Fab")
		)
		(pad "1" smd rect
			(at 0 0 90)
			(size 0.508 0.508)
			(layers "F.Cu" "F.Mask" "F.Paste")
			(net "P5V_STBY")
		)
		(pad "2" smd rect
			(at 0 0.889 90)
			(size 0.508 0.508)
			(layers "F.Cu" "F.Mask" "F.Paste")
			(net "GND")
		)
		(zone
			(layer "F.Cu")
			(hatch none 0.5)
			(connect_pads
				(clearance 0)
			)
			(min_thickness 0.25)
			(keepout
				(tracks allowed)
				(vias not_allowed)
				(pads allowed)
				(copperpour not_allowed)
				(footprints allowed)
			)
			(placement
				(enabled no)
				(sheetname "")
			)
			(fill
				(thermal_gap 0.5)
				(thermal_bridge_width 0.5)
				(island_removal_mode 0)
			)
			(polygon
				(pts
					(xy 33.762696 -69.6722) (xy 33.381696 -69.6722) (xy 33.381696 -69.1642) (xy 33.762696 -69.1642)
				)
			)
		)
		(zone
			(layer "F.Cu")
			(hatch none 0.5)
			(connect_pads
				(clearance 0)
			)
			(min_thickness 0.25)
			(keepout
				(tracks not_allowed)
				(vias allowed)
				(pads allowed)
				(copperpour not_allowed)
				(footprints allowed)
			)
			(placement
				(enabled no)
				(sheetname "")
			)
			(fill
				(thermal_gap 0.5)
				(thermal_bridge_width 0.5)
				(island_removal_mode 0)
			)
			(polygon
				(pts
					(xy 33.762696 -69.6722) (xy 33.381696 -69.6722) (xy 33.381696 -69.1642) (xy 33.762696 -69.1642)
				)
			)
		)
	)
	(footprint ""
		(layer "F.Cu")
		(at 245.7577 -3.3528 -90)
		(property "Reference" "C5G11"
			(at 1.848866 0.752348 270)
			(unlocked yes)
			(layer "F.SilkS")
			(effects
				(font
					(size 1.27 0.9652)
					(thickness 0.1524)
				)
			)
		)
		(property "Value" ""
			(at 0 0 270)
			(layer "F.Fab")
			(effects
				(font
					(size 1.27 1.27)
				)
			)
		)
		(duplicate_pad_numbers_are_jumpers no)
		(fp_rect
			(start -0.500126 1.598422)
			(end 0.500126 -0.201422)
			(stroke
				(width 0)
				(type default)
			)
			(fill no)
			(layer "F.CrtYd")
		)
		(fp_line
			(start -0.500126 1.598422)
			(end -0.500126 -0.201422)
			(stroke
				(width 0.1)
				(type default)
			)
			(layer "F.Fab")
		)
		(fp_line
			(start 0.500126 1.598422)
			(end -0.500126 1.598422)
			(stroke
				(width 0.1)
				(type default)
			)
			(layer "F.Fab")
		)
		(fp_line
			(start -0.500126 -0.201422)
			(end 0.500126 -0.201422)
			(stroke
				(width 0.1)
				(type default)
			)
			(layer "F.Fab")
		)
		(fp_line
			(start 0.500126 -0.201422)
			(end 0.500126 1.598422)
			(stroke
				(width 0.1)
				(type default)
			)
			(layer "F.Fab")
		)
		(pad "1" smd rect
			(at 0 0 180)
			(size 0.889 0.9906)
			(layers "F.Cu" "F.Mask" "F.Paste")
			(net "PVDDQ_ABC")
		)
		(pad "2" smd rect
			(at 0 1.397 180)
			(size 0.889 0.9906)
			(layers "F.Cu" "F.Mask" "F.Paste")
			(net "GND")
		)
		(zone
			(layer "F.Cu")
			(hatch none 0.5)
			(connect_pads
				(clearance 0)
			)
			(min_thickness 0.25)
			(keepout
				(tracks allowed)
				(vias not_allowed)
				(pads allowed)
				(copperpour not_allowed)
				(footprints allowed)
			)
			(placement
				(enabled no)
				(sheetname "")
			)
			(fill
				(thermal_gap 0.5)
				(thermal_bridge_width 0.5)
				(island_removal_mode 0)
			)
			(polygon
				(pts
					(xy 244.8052 -3.8481) (xy 244.8052 -2.8575) (xy 245.3132 -2.8575) (xy 245.3132 -3.8481)
				)
			)
		)
		(zone
			(layer "F.Cu")
			(hatch none 0.5)
			(connect_pads
				(clearance 0)
			)
			(min_thickness 0.25)
			(keepout
				(tracks not_allowed)
				(vias allowed)
				(pads allowed)
				(copperpour not_allowed)
				(footprints allowed)
			)
			(placement
				(enabled no)
				(sheetname "")
			)
			(fill
				(thermal_gap 0.5)
				(thermal_bridge_width 0.5)
				(island_removal_mode 0)
			)
			(polygon
				(pts
					(xy 244.8052 -3.8481) (xy 244.8052 -2.8575) (xy 245.3132 -2.8575) (xy 245.3132 -3.8481)
				)
			)
		)
	)
	(footprint ""
		(layer "F.Cu")
		(at 413.3215 -113.411 -90)
		(property "Reference" "R2L4"
			(at 0 0 270)
			(layer "F.SilkS")
			(hide yes)
			(effects
				(font
					(size 1.27 1.27)
				)
			)
		)
		(property "Value" ""
			(at 0 0 270)
			(layer "F.Fab")
			(effects
				(font
					(size 1.27 1.27)
				)
			)
		)
		(duplicate_pad_numbers_are_jumpers no)
		(fp_poly
			(pts
				(xy -0.2794 -0.1016) (xy 0.2794 -0.1016) (xy 0.2794 0.9906) (xy -0.2794 0.9906)
			)
			(stroke
				(width 0)
				(type default)
			)
			(fill no)
			(layer "F.CrtYd")
		)
		(fp_line
			(start -0.2794 0.9906)
			(end 0.2794 0.9906)
			(stroke
				(width 0.1)
				(type default)
			)
			(layer "F.Fab")
		)
		(fp_line
			(start 0.2794 0.9906)
			(end 0.2794 -0.1016)
			(stroke
				(width 0.1)
				(type default)
			)
			(layer "F.Fab")
		)
		(fp_line
			(start -0.2794 -0.1016)
			(end -0.2794 0.9906)
			(stroke
				(width 0.1)
				(type default)
			)
			(layer "F.Fab")
		)
		(fp_line
			(start 0.2794 -0.1016)
			(end -0.2794 -0.1016)
			(stroke
				(width 0.1)
				(type default)
			)
			(layer "F.Fab")
		)
		(pad "1" smd rect
			(at 0 0 270)
			(size 0.508 0.508)
			(layers "F.Cu" "F.Mask" "F.Paste")
			(net "P3V3_STBY")
		)
		(pad "2" smd rect
			(at 0 0.889 270)
			(size 0.508 0.508)
			(layers "F.Cu" "F.Mask" "F.Paste")
			(net "SGPIO_PCH_SSATA_DOUT0_R")
		)
		(zone
			(layer "F.Cu")
			(hatch none 0.5)
			(connect_pads
				(clearance 0)
			)
			(min_thickness 0.25)
			(keepout
				(tracks not_allowed)
				(vias allowed)
				(pads allowed)
				(copperpour not_allowed)
				(footprints allowed)
			)
			(placement
				(enabled no)
				(sheetname "")
			)
			(fill
				(thermal_gap 0.5)
				(thermal_bridge_width 0.5)
				(island_removal_mode 0)
			)
			(polygon
				(pts
					(xy 412.6865 -113.665) (xy 412.6865 -113.157) (xy 413.0675 -113.157) (xy 413.0675 -113.665)
				)
			)
		)
		(zone
			(layer "F.Cu")
			(hatch none 0.5)
			(connect_pads
				(clearance 0)
			)
			(min_thickness 0.25)
			(keepout
				(tracks allowed)
				(vias not_allowed)
				(pads allowed)
				(copperpour not_allowed)
				(footprints allowed)
			)
			(placement
				(enabled no)
				(sheetname "")
			)
			(fill
				(thermal_gap 0.5)
				(thermal_bridge_width 0.5)
				(island_removal_mode 0)
			)
			(polygon
				(pts
					(xy 413.0675 -113.665) (xy 413.0675 -113.157) (xy 412.6865 -113.157) (xy 412.6865 -113.665)
				)
			)
		)
	)
)
